(kicad_pcb
	(version 20260206)
	(generator "pcbnew")
	(generator_version "10.0")
	(general
		(thickness 1.6)
		(legacy_teardrops no)
	)
	(paper "A4")
	(title_block
		(title "v1-chassis-manager — T6M_CM_d_v01_1031_1645.brd")
		(comment 1 "Open CloudServer (Microsoft) / footprints 751-760 of 2512")
	)
	(layers
		(0 "F.Cu" signal "TOP")
		(4 "In1.Cu" signal "GND1")
		(6 "In2.Cu" signal "IN1")
		(8 "In3.Cu" signal "VCC1")
		(10 "In4.Cu" signal "VCC2")
		(12 "In5.Cu" signal "GND2")
		(14 "In6.Cu" signal "IN2")
		(16 "In7.Cu" signal "IN3")
		(18 "In8.Cu" signal "GND3")
		(2 "B.Cu" signal "BOTTOM")
		(9 "F.Adhes" user "F.Adhesive")
		(11 "B.Adhes" user "B.Adhesive")
		(13 "F.Paste" user "Package Geometry/Pastemask Top")
		(15 "B.Paste" user "Package Geometry/Pastemask Bottom")
		(5 "F.SilkS" user "Ref Des/Silkscreen Top")
		(7 "B.SilkS" user "Ref Des/Silkscreen Bottom")
		(1 "F.Mask" user "Board Geometry/Soldermask Top")
		(3 "B.Mask" user "Board Geometry/Soldermask Bottom")
		(17 "Dwgs.User" user "User.Drawings")
		(19 "Cmts.User" user "User.Comments")
		(21 "Eco1.User" user "User.Eco1")
		(23 "Eco2.User" user "User.Eco2")
		(25 "Edge.Cuts" user "Board Geometry/Outline")
		(27 "Margin" user)
		(31 "F.CrtYd" user "Package Geometry/Place Bound Top")
		(29 "B.CrtYd" user "Package Geometry/Place Bound Bottom")
		(35 "F.Fab" user "Ref Des/Assembly Top")
		(33 "B.Fab" user "Ref Des/Assembly Bottom")
	)
	(footprint ""
		(layer "F.Cu")
		(at 144.678146 -154.610816 -90)
		(property "Reference" "U13"
			(at 3.071622 0.10668 0)
			(unlocked yes)
			(layer "F.SilkS")
			(effects
				(font
					(size 0.7874 0.5842)
					(thickness 0.1524)
				)
				(justify left)
			)
		)
		(property "Value" ""
			(at 0 0 270)
			(layer "F.Fab")
			(effects
				(font
					(size 1.27 1.27)
				)
			)
		)
		(duplicate_pad_numbers_are_jumpers no)
		(fp_line
			(start -2.5146 1.4224)
			(end -2.5146 0.4572)
			(stroke
				(width 0.1524)
				(type default)
			)
			(layer "F.SilkS")
		)
		(fp_line
			(start 2.5146 1.4224)
			(end -2.5146 1.4224)
			(stroke
				(width 0.1524)
				(type default)
			)
			(layer "F.SilkS")
		)
		(fp_line
			(start -2.5146 0.4572)
			(end -2.0574 0)
			(stroke
				(width 0.1524)
				(type default)
			)
			(layer "F.SilkS")
		)
		(fp_line
			(start -2.0574 0)
			(end -2.5146 -0.4572)
			(stroke
				(width 0.1524)
				(type default)
			)
			(layer "F.SilkS")
		)
		(fp_line
			(start -2.5146 -0.4572)
			(end -2.5146 -1.4224)
			(stroke
				(width 0.1524)
				(type default)
			)
			(layer "F.SilkS")
		)
		(fp_line
			(start -2.5146 -1.4224)
			(end 2.5146 -1.4224)
			(stroke
				(width 0.1524)
				(type default)
			)
			(layer "F.SilkS")
		)
		(fp_line
			(start 2.5146 -1.4224)
			(end 2.5146 1.4224)
			(stroke
				(width 0.1524)
				(type default)
			)
			(layer "F.SilkS")
		)
		(fp_circle
			(center -1.905 0.889)
			(end -1.905 0.635)
			(stroke
				(width 0.1524)
				(type default)
			)
			(fill no)
			(layer "F.SilkS")
		)
		(fp_poly
			(pts
				(xy -2.1844 3.5052) (xy -2.1844 2.0066) (xy -2.5146 2.0066) (xy -2.5146 -2.0066) (xy -2.1844 -2.0066)
				(xy -2.1844 -3.5052) (xy 2.1844 -3.5052) (xy 2.1844 -2.0066) (xy 2.5146 -2.0066) (xy 2.5146 2.0066)
				(xy 2.1844 2.0066) (xy 2.1844 3.5052)
			)
			(stroke
				(width 0)
				(type default)
			)
			(fill no)
			(layer "F.CrtYd")
		)
		(pad "1" smd rect
			(at -1.905 2.6416 270)
			(size 0.5588 1.7272)
			(layers "F.Cu" "F.Mask" "F.Paste")
			(net "N49382752")
		)
		(pad "2" smd rect
			(at -0.635 2.6416 270)
			(size 0.5588 1.7272)
			(layers "F.Cu" "F.Mask" "F.Paste")
			(net "N49382752")
		)
		(pad "3" smd rect
			(at 0.635 2.6416 270)
			(size 0.5588 1.7272)
			(layers "F.Cu" "F.Mask" "F.Paste")
			(net "N49382752")
		)
		(pad "4" smd rect
			(at 1.905 2.6416 270)
			(size 0.5588 1.7272)
			(layers "F.Cu" "F.Mask" "F.Paste")
			(net "GND")
		)
		(pad "5" smd rect
			(at 1.905 -2.6416 270)
			(size 0.5588 1.7272)
			(layers "F.Cu" "F.Mask" "F.Paste")
			(net "PCIE_SW_EEPROM_DAT")
		)
		(pad "6" smd rect
			(at 0.635 -2.6416 270)
			(size 0.5588 1.7272)
			(layers "F.Cu" "F.Mask" "F.Paste")
			(net "PCIE_SW_EEPROM_CLK")
		)
		(pad "7" smd rect
			(at -0.635 -2.6416 270)
			(size 0.5588 1.7272)
			(layers "F.Cu" "F.Mask" "F.Paste")
			(net "PCIE_SW_WP_N")
		)
		(pad "8" smd rect
			(at -1.905 -2.6416 270)
			(size 0.5588 1.7272)
			(layers "F.Cu" "F.Mask" "F.Paste")
			(net "P3V3_NODE1")
		)
	)
	(footprint ""
		(layer "F.Cu")
		(at 100.626672 -159.571182 180)
		(property "Reference" "R1232"
			(at -86.995 -70.789292 0)
			(unlocked yes)
			(layer "F.SilkS")
			(effects
				(font
					(size 0.7874 0.5842)
					(thickness 0.1524)
				)
				(justify left)
			)
		)
		(property "Value" ""
			(at 0 0 180)
			(layer "F.Fab")
			(effects
				(font
					(size 1.27 1.27)
				)
			)
		)
		(duplicate_pad_numbers_are_jumpers no)
		(fp_line
			(start 0.7874 0.4064)
			(end -0.7874 0.4064)
			(stroke
				(width 0.1524)
				(type default)
			)
			(layer "F.SilkS")
		)
		(fp_line
			(start 0.7874 -0.4064)
			(end 0.7874 0.4064)
			(stroke
				(width 0.1524)
				(type default)
			)
			(layer "F.SilkS")
		)
		(fp_line
			(start -0.7874 0.4064)
			(end -0.7874 -0.4064)
			(stroke
				(width 0.1524)
				(type default)
			)
			(layer "F.SilkS")
		)
		(fp_line
			(start -0.7874 -0.4064)
			(end 0.7874 -0.4064)
			(stroke
				(width 0.1524)
				(type default)
			)
			(layer "F.SilkS")
		)
		(fp_poly
			(pts
				(xy -0.508 0.2794) (xy -0.508 0.2286) (xy -0.635 0.2286) (xy -0.635 -0.254) (xy -0.5334 -0.254)
				(xy -0.5334 -0.2794) (xy 0.5334 -0.2794) (xy 0.5334 -0.254) (xy 0.635 -0.254) (xy 0.635 0.254) (xy 0.5334 0.254)
				(xy 0.5334 0.2794)
			)
			(stroke
				(width 0)
				(type default)
			)
			(fill no)
			(layer "F.CrtYd")
		)
		(pad "1" smd rect
			(at 0.40005 0 180)
			(size 0.4572 0.508)
			(layers "F.Cu" "F.Mask" "F.Paste")
			(net "GND")
		)
		(pad "2" smd rect
			(at -0.40005 0 180)
			(size 0.4572 0.508)
			(layers "F.Cu" "F.Mask" "F.Paste")
			(net "FM_CPLD_NODE1_P1V8_STB_EN")
		)
	)
	(footprint ""
		(layer "F.Cu")
		(at 36.88334 -14.24559 90)
		(property "Reference" "PC85"
			(at -0.985012 -3.4925 90)
			(unlocked yes)
			(layer "F.SilkS")
			(effects
				(font
					(size 0.7874 0.5842)
					(thickness 0.1524)
				)
				(justify left)
			)
		)
		(property "Value" ""
			(at 0 0 90)
			(layer "F.Fab")
			(effects
				(font
					(size 1.27 1.27)
				)
			)
		)
		(duplicate_pad_numbers_are_jumpers no)
		(fp_line
			(start 0.7874 -0.4064)
			(end 0.7874 0.4064)
			(stroke
				(width 0.1524)
				(type default)
			)
			(layer "F.SilkS")
		)
		(fp_line
			(start -0.7874 -0.4064)
			(end 0.7874 -0.4064)
			(stroke
				(width 0.1524)
				(type default)
			)
			(layer "F.SilkS")
		)
		(fp_line
			(start 0 0.381)
			(end 0 -0.381)
			(stroke
				(width 0.1524)
				(type default)
			)
			(layer "F.SilkS")
		)
		(fp_line
			(start 0.7874 0.4064)
			(end -0.7874 0.4064)
			(stroke
				(width 0.1524)
				(type default)
			)
			(layer "F.SilkS")
		)
		(fp_line
			(start -0.7874 0.4064)
			(end -0.7874 -0.4064)
			(stroke
				(width 0.1524)
				(type default)
			)
			(layer "F.SilkS")
		)
		(fp_poly
			(pts
				(xy -0.5334 0.254) (xy -0.635 0.254) (xy -0.635 0.2286) (xy -0.635 -0.254) (xy -0.5334 -0.254) (xy -0.5334 -0.2794)
				(xy 0.5334 -0.2794) (xy 0.5334 -0.254) (xy 0.635 -0.254) (xy 0.635 0.254) (xy 0.5334 0.254) (xy 0.5334 0.2794)
				(xy -0.508 0.2794) (xy -0.5334 0.2794)
			)
			(stroke
				(width 0)
				(type default)
			)
			(fill no)
			(layer "F.CrtYd")
		)
		(pad "1" smd rect
			(at 0.40005 0 90)
			(size 0.4572 0.508)
			(layers "F.Cu" "F.Mask" "F.Paste")
			(net "GND")
		)
		(pad "2" smd rect
			(at -0.40005 0 90)
			(size 0.4572 0.508)
			(layers "F.Cu" "F.Mask" "F.Paste")
			(net "PV_VDDR_NODE1_SLEW")
		)
	)
	(footprint ""
		(layer "F.Cu")
		(at 66.491358 -9.506966 180)
		(property "Reference" "PR20"
			(at 1.450086 4.40055 0)
			(unlocked yes)
			(layer "F.SilkS")
			(effects
				(font
					(size 0.7874 0.5842)
					(thickness 0.1524)
				)
				(justify left)
			)
		)
		(property "Value" ""
			(at 0 0 180)
			(layer "F.Fab")
			(effects
				(font
					(size 1.27 1.27)
				)
			)
		)
		(duplicate_pad_numbers_are_jumpers no)
		(fp_line
			(start 0.7874 0.4064)
			(end -0.7874 0.4064)
			(stroke
				(width 0.1524)
				(type default)
			)
			(layer "F.SilkS")
		)
		(fp_line
			(start 0.7874 -0.4064)
			(end 0.7874 0.4064)
			(stroke
				(width 0.1524)
				(type default)
			)
			(layer "F.SilkS")
		)
		(fp_line
			(start -0.7874 0.4064)
			(end -0.7874 -0.4064)
			(stroke
				(width 0.1524)
				(type default)
			)
			(layer "F.SilkS")
		)
		(fp_line
			(start -0.7874 -0.4064)
			(end 0.7874 -0.4064)
			(stroke
				(width 0.1524)
				(type default)
			)
			(layer "F.SilkS")
		)
		(fp_poly
			(pts
				(xy -0.508 0.2794) (xy -0.508 0.2286) (xy -0.635 0.2286) (xy -0.635 -0.254) (xy -0.5334 -0.254)
				(xy -0.5334 -0.2794) (xy 0.5334 -0.2794) (xy 0.5334 -0.254) (xy 0.635 -0.254) (xy 0.635 0.254) (xy 0.5334 0.254)
				(xy 0.5334 0.2794)
			)
			(stroke
				(width 0)
				(type default)
			)
			(fill no)
			(layer "F.CrtYd")
		)
		(pad "1" smd rect
			(at 0.40005 0 180)
			(size 0.4572 0.508)
			(layers "F.Cu" "F.Mask" "F.Paste")
			(net "P3V3_NODE1_FB")
		)
		(pad "2" smd rect
			(at -0.40005 0 180)
			(size 0.4572 0.508)
			(layers "F.Cu" "F.Mask" "F.Paste")
			(net "P3V3_NODE1")
		)
	)
	(footprint ""
		(layer "F.Cu")
		(at 139.676886 -51.476656 90)
		(property "Reference" "R1020"
			(at 16.324326 30.427168 90)
			(unlocked yes)
			(layer "F.SilkS")
			(effects
				(font
					(size 0.7874 0.5842)
					(thickness 0.1524)
				)
				(justify left)
			)
		)
		(property "Value" ""
			(at 0 0 90)
			(layer "F.Fab")
			(effects
				(font
					(size 1.27 1.27)
				)
			)
		)
		(duplicate_pad_numbers_are_jumpers no)
		(fp_line
			(start 0.7874 -0.4064)
			(end 0.7874 0.4064)
			(stroke
				(width 0.1524)
				(type default)
			)
			(layer "F.SilkS")
		)
		(fp_line
			(start -0.7874 -0.4064)
			(end 0.7874 -0.4064)
			(stroke
				(width 0.1524)
				(type default)
			)
			(layer "F.SilkS")
		)
		(fp_line
			(start 0.7874 0.4064)
			(end -0.7874 0.4064)
			(stroke
				(width 0.1524)
				(type default)
			)
			(layer "F.SilkS")
		)
		(fp_line
			(start -0.7874 0.4064)
			(end -0.7874 -0.4064)
			(stroke
				(width 0.1524)
				(type default)
			)
			(layer "F.SilkS")
		)
		(fp_poly
			(pts
				(xy -0.508 0.2794) (xy -0.508 0.2286) (xy -0.635 0.2286) (xy -0.635 -0.254) (xy -0.5334 -0.254)
				(xy -0.5334 -0.2794) (xy 0.5334 -0.2794) (xy 0.5334 -0.254) (xy 0.635 -0.254) (xy 0.635 0.254) (xy 0.5334 0.254)
				(xy 0.5334 0.2794)
			)
			(stroke
				(width 0)
				(type default)
			)
			(fill no)
			(layer "F.CrtYd")
		)
		(pad "1" smd rect
			(at 0.40005 0 90)
			(size 0.4572 0.508)
			(layers "F.Cu" "F.Mask" "F.Paste")
			(net "P5V_NODE1")
		)
		(pad "2" smd rect
			(at -0.40005 0 90)
			(size 0.4572 0.508)
			(layers "F.Cu" "F.Mask" "F.Paste")
			(net "UART_TX_P2")
		)
	)
	(footprint ""
		(layer "F.Cu")
		(at 79.077566 -158.46298)
		(property "Reference" "PJ1"
			(at 3.839464 1.161796 90)
			(unlocked yes)
			(layer "F.SilkS")
			(effects
				(font
					(size 0.7874 0.5842)
					(thickness 0.1524)
				)
				(justify left)
			)
		)
		(property "Value" ""
			(at 0 0 0)
			(layer "F.Fab")
			(effects
				(font
					(size 1.27 1.27)
				)
			)
		)
		(duplicate_pad_numbers_are_jumpers no)
		(fp_poly
			(pts
				(xy 0.2794 0.907796) (xy 0.254 0.907796) (xy 0.254 1.0414) (xy -0.254 1.0414) (xy -0.254 1.034796)
				(xy -0.254 0.933196) (xy -0.2794 0.933196) (xy -0.2794 -0.133604) (xy -0.254 -0.133604) (xy -0.254 -0.235204)
				(xy 0.254 -0.235204) (xy 0.254 -0.133604) (xy 0.2794 -0.133604)
			)
			(stroke
				(width 0)
				(type default)
			)
			(fill no)
			(layer "F.CrtYd")
		)
		(pad "1" smd custom
			(at 0 -0.000254)
			(size 0.127 0.127)
			(layers "F.Cu" "F.Mask" "F.Paste")
			(net "P5V_STB_NODE1_EN")
			(options
				(clearance outline)
				(anchor circle)
			)
			(primitives
				(gr_poly
					(pts
						(xy -0.127 0.508) (xy -0.127 -0.0508) (xy -0.254 -0.0508) (xy -0.254 -0.508) (xy 0.254 -0.508)
						(xy 0.254 -0.0508) (xy 0.127 -0.0508) (xy 0.127 0.508)
					)
					(width 0)
					(fill yes)
				)
			)
		)
		(pad "2" smd rect
			(at 0 0.799846 90)
			(size 0.4572 0.508)
			(layers "F.Cu" "F.Mask" "F.Paste")
			(net "P5V_STB_NODE1_EN_P")
		)
		(zone
			(layer "F.Cu")
			(hatch none 0.5)
			(connect_pads
				(clearance 0)
			)
			(min_thickness 0.25)
			(keepout
				(tracks allowed)
				(vias not_allowed)
				(pads allowed)
				(copperpour not_allowed)
				(footprints allowed)
			)
			(placement
				(enabled no)
				(sheetname "")
			)
			(fill
				(thermal_gap 0.5)
				(thermal_bridge_width 0.5)
				(island_removal_mode 0)
			)
			(polygon
				(pts
					(xy 78.772766 -157.377384) (xy 79.382366 -157.377384) (xy 79.382366 -158.748984) (xy 78.772766 -158.748984)
				)
			)
		)
	)
	(footprint ""
		(layer "F.Cu")
		(at 144.738852 -147.19935)
		(property "Reference" "R306"
			(at -0.526288 18.534888 0)
			(unlocked yes)
			(layer "F.SilkS")
			(effects
				(font
					(size 0.7874 0.5842)
					(thickness 0.1524)
				)
				(justify left)
			)
		)
		(property "Value" ""
			(at 0 0 0)
			(layer "F.Fab")
			(effects
				(font
					(size 1.27 1.27)
				)
			)
		)
		(duplicate_pad_numbers_are_jumpers no)
		(fp_line
			(start -0.7874 -0.4064)
			(end 0.7874 -0.4064)
			(stroke
				(width 0.1524)
				(type default)
			)
			(layer "F.SilkS")
		)
		(fp_line
			(start -0.7874 0.4064)
			(end -0.7874 -0.4064)
			(stroke
				(width 0.1524)
				(type default)
			)
			(layer "F.SilkS")
		)
		(fp_line
			(start 0.7874 -0.4064)
			(end 0.7874 0.4064)
			(stroke
				(width 0.1524)
				(type default)
			)
			(layer "F.SilkS")
		)
		(fp_line
			(start 0.7874 0.4064)
			(end -0.7874 0.4064)
			(stroke
				(width 0.1524)
				(type default)
			)
			(layer "F.SilkS")
		)
		(fp_poly
			(pts
				(xy -0.508 0.2794) (xy -0.508 0.2286) (xy -0.635 0.2286) (xy -0.635 -0.254) (xy -0.5334 -0.254)
				(xy -0.5334 -0.2794) (xy 0.5334 -0.2794) (xy 0.5334 -0.254) (xy 0.635 -0.254) (xy 0.635 0.254) (xy 0.5334 0.254)
				(xy 0.5334 0.2794)
			)
			(stroke
				(width 0)
				(type default)
			)
			(fill no)
			(layer "F.CrtYd")
		)
		(pad "1" smd rect
			(at 0.40005 0)
			(size 0.4572 0.508)
			(layers "F.Cu" "F.Mask" "F.Paste")
			(net "GND")
		)
		(pad "2" smd rect
			(at -0.40005 0)
			(size 0.4572 0.508)
			(layers "F.Cu" "F.Mask" "F.Paste")
			(net "PCIE_SW_GPIO6")
		)
	)
	(footprint ""
		(layer "F.Cu")
		(at 106.069638 -140.815822 180)
		(property "Reference" "PR77"
			(at 1.345946 3.26009 0)
			(unlocked yes)
			(layer "F.SilkS")
			(effects
				(font
					(size 0.635 0.4064)
					(thickness 0.1524)
				)
				(justify left)
			)
		)
		(property "Value" ""
			(at 0 0 180)
			(layer "F.Fab")
			(effects
				(font
					(size 1.27 1.27)
				)
			)
		)
		(duplicate_pad_numbers_are_jumpers no)
		(fp_line
			(start 0.7874 0.4064)
			(end -0.7874 0.4064)
			(stroke
				(width 0.1524)
				(type default)
			)
			(layer "F.SilkS")
		)
		(fp_line
			(start 0.7874 -0.4064)
			(end 0.7874 0.4064)
			(stroke
				(width 0.1524)
				(type default)
			)
			(layer "F.SilkS")
		)
		(fp_line
			(start -0.7874 0.4064)
			(end -0.7874 -0.4064)
			(stroke
				(width 0.1524)
				(type default)
			)
			(layer "F.SilkS")
		)
		(fp_line
			(start -0.7874 -0.4064)
			(end 0.7874 -0.4064)
			(stroke
				(width 0.1524)
				(type default)
			)
			(layer "F.SilkS")
		)
		(fp_poly
			(pts
				(xy -0.508 0.2794) (xy -0.508 0.2286) (xy -0.635 0.2286) (xy -0.635 -0.254) (xy -0.5334 -0.254)
				(xy -0.5334 -0.2794) (xy 0.5334 -0.2794) (xy 0.5334 -0.254) (xy 0.635 -0.254) (xy 0.635 0.254) (xy 0.5334 0.254)
				(xy 0.5334 0.2794)
			)
			(stroke
				(width 0)
				(type default)
			)
			(fill no)
			(layer "F.CrtYd")
		)
		(pad "1" smd rect
			(at 0.40005 0 180)
			(size 0.4572 0.508)
			(layers "F.Cu" "F.Mask" "F.Paste")
			(net "AGND_PVCCP_NODE1")
		)
		(pad "2" smd rect
			(at -0.40005 0 180)
			(size 0.4572 0.508)
			(layers "F.Cu" "F.Mask" "F.Paste")
			(net "VR_PVCCP_NODE1_OCSET")
		)
	)
	(footprint ""
		(layer "F.Cu")
		(at 79.963518 -90.011504 180)
		(property "Reference" "R166"
			(at 1.195578 -18.994374 0)
			(unlocked yes)
			(layer "F.SilkS")
			(effects
				(font
					(size 0.7874 0.5842)
					(thickness 0.1524)
				)
				(justify left)
			)
		)
		(property "Value" ""
			(at 0 0 180)
			(layer "F.Fab")
			(effects
				(font
					(size 1.27 1.27)
				)
			)
		)
		(duplicate_pad_numbers_are_jumpers no)
		(fp_line
			(start 0.7874 0.4064)
			(end -0.7874 0.4064)
			(stroke
				(width 0.1524)
				(type default)
			)
			(layer "F.SilkS")
		)
		(fp_line
			(start 0.7874 -0.4064)
			(end 0.7874 0.4064)
			(stroke
				(width 0.1524)
				(type default)
			)
			(layer "F.SilkS")
		)
		(fp_line
			(start -0.7874 0.4064)
			(end -0.7874 -0.4064)
			(stroke
				(width 0.1524)
				(type default)
			)
			(layer "F.SilkS")
		)
		(fp_line
			(start -0.7874 -0.4064)
			(end 0.7874 -0.4064)
			(stroke
				(width 0.1524)
				(type default)
			)
			(layer "F.SilkS")
		)
		(fp_poly
			(pts
				(xy -0.508 0.2794) (xy -0.508 0.2286) (xy -0.635 0.2286) (xy -0.635 -0.254) (xy -0.5334 -0.254)
				(xy -0.5334 -0.2794) (xy 0.5334 -0.2794) (xy 0.5334 -0.254) (xy 0.635 -0.254) (xy 0.635 0.254) (xy 0.5334 0.254)
				(xy 0.5334 0.2794)
			)
			(stroke
				(width 0)
				(type default)
			)
			(fill no)
			(layer "F.CrtYd")
		)
		(pad "1" smd rect
			(at 0.40005 0 180)
			(size 0.4572 0.508)
			(layers "F.Cu" "F.Mask" "F.Paste")
			(net "VR_CPU_NODE1_INTVRMEN")
		)
		(pad "2" smd rect
			(at -0.40005 0 180)
			(size 0.4572 0.508)
			(layers "F.Cu" "F.Mask" "F.Paste")
			(net "GND")
		)
	)
	(footprint ""
		(layer "F.Cu")
		(at 171.151042 -138.367008)
		(property "Reference" "R1054"
			(at -2.942082 -9.390888 0)
			(unlocked yes)
			(layer "F.SilkS")
			(effects
				(font
					(size 0.7874 0.5842)
					(thickness 0.1524)
				)
				(justify left)
			)
		)
		(property "Value" ""
			(at 0 0 0)
			(layer "F.Fab")
			(effects
				(font
					(size 1.27 1.27)
				)
			)
		)
		(duplicate_pad_numbers_are_jumpers no)
		(fp_line
			(start -0.7874 -0.4064)
			(end 0.7874 -0.4064)
			(stroke
				(width 0.1524)
				(type default)
			)
			(layer "F.SilkS")
		)
		(fp_line
			(start -0.7874 0.4064)
			(end -0.7874 -0.4064)
			(stroke
				(width 0.1524)
				(type default)
			)
			(layer "F.SilkS")
		)
		(fp_line
			(start 0.7874 -0.4064)
			(end 0.7874 0.4064)
			(stroke
				(width 0.1524)
				(type default)
			)
			(layer "F.SilkS")
		)
		(fp_line
			(start 0.7874 0.4064)
			(end -0.7874 0.4064)
			(stroke
				(width 0.1524)
				(type default)
			)
			(layer "F.SilkS")
		)
		(fp_poly
			(pts
				(xy -0.508 0.2794) (xy -0.508 0.2286) (xy -0.635 0.2286) (xy -0.635 -0.254) (xy -0.5334 -0.254)
				(xy -0.5334 -0.2794) (xy 0.5334 -0.2794) (xy 0.5334 -0.254) (xy 0.635 -0.254) (xy 0.635 0.254) (xy 0.5334 0.254)
				(xy 0.5334 0.2794)
			)
			(stroke
				(width 0)
				(type default)
			)
			(fill no)
			(layer "F.CrtYd")
		)
		(pad "1" smd rect
			(at 0.40005 0)
			(size 0.4572 0.508)
			(layers "F.Cu" "F.Mask" "F.Paste")
			(net "PWR_BTN_NODE1_C_L")
		)
		(pad "2" smd rect
			(at -0.40005 0)
			(size 0.4572 0.508)
			(layers "F.Cu" "F.Mask" "F.Paste")
			(net "PWR_BTN_NODE1_L")
		)
	)
)
